(kicad_pcb
	(version 20260206)
	(generator "pcbnew")
	(generator_version "10.0")
	(general
		(thickness 1.6)
		(legacy_teardrops no)
	)
	(paper "A4")
	(title_block
		(title "m-2 — Lightning_M.2_BRD.brd")
		(comment 1 "Lightning (Wiwynn / Facebook NVMe JBOF) / footprints 84-92 of 157")
	)
	(layers
		(0 "F.Cu" signal "TOP")
		(4 "In1.Cu" signal "L2GND")
		(6 "In2.Cu" signal "L3")
		(8 "In3.Cu" signal "L4GND")
		(10 "In4.Cu" signal "L5GND")
		(12 "In5.Cu" signal "L6")
		(14 "In6.Cu" signal "L7GND")
		(2 "B.Cu" signal "BOTTOM")
		(9 "F.Adhes" user "F.Adhesive")
		(11 "B.Adhes" user "B.Adhesive")
		(13 "F.Paste" user "Package Geometry/Pastemask Top")
		(15 "B.Paste" user "Package Geometry/Pastemask Bottom")
		(5 "F.SilkS" user "Ref Des/Silkscreen Top")
		(7 "B.SilkS" user "Ref Des/Silkscreen Bottom")
		(1 "F.Mask" user "Board Geometry/Soldermask Top")
		(3 "B.Mask" user "Board Geometry/Soldermask Bottom")
		(17 "Dwgs.User" user "User.Drawings")
		(19 "Cmts.User" user "User.Comments")
		(21 "Eco1.User" user "User.Eco1")
		(23 "Eco2.User" user "User.Eco2")
		(25 "Edge.Cuts" user "Board Geometry/Outline")
		(27 "Margin" user)
		(31 "F.CrtYd" user "Package Geometry/Place Bound Top")
		(29 "B.CrtYd" user "Package Geometry/Place Bound Bottom")
		(35 "F.Fab" user "Ref Des/Assembly Top")
		(33 "B.Fab" user "Ref Des/Assembly Bottom")
	)
	(footprint ""
		(layer "F.Cu")
		(at 60.200032 -4.500118)
		(property "Reference" "H3"
			(at 0 0 0)
			(layer "F.SilkS")
			(hide yes)
			(effects
				(font
					(size 1.27 1.27)
				)
			)
		)
		(property "Value" "HOLE315R140-GP"
			(at 0 -7.5692 0)
			(unlocked yes)
			(layer "F.Fab")
			(hide yes)
			(effects
				(font
					(size 1.016 1.016)
					(thickness 0.1524)
				)
			)
		)
		(property "Device Type" "HOLE315R140"
			(at 0 -9.0932 0)
			(unlocked yes)
			(layer "F.Fab")
			(hide yes)
			(effects
				(font
					(size 1.016 1.016)
					(thickness 0.1524)
				)
			)
		)
		(duplicate_pad_numbers_are_jumpers no)
		(fp_poly
			(pts
				(arc
					(start 4.3053 0)
					(mid -4.3053 0)
					(end 4.3053 0)
				)
			)
			(stroke
				(width 0)
				(type default)
			)
			(fill no)
			(layer "F.CrtYd")
		)
		(fp_poly
			(pts
				(arc
					(start 4.3053 0)
					(mid -4.3053 0)
					(end 4.3053 0)
				)
			)
			(stroke
				(width 0)
				(type default)
			)
			(fill no)
			(layer "F.Fab")
		)
		(pad "1" thru_hole circle
			(at 0.00127 0.00127)
			(size 8.001 8.001)
			(drill 3.556)
			(layers "*.Cu" "*.Mask")
			(remove_unused_layers no)
			(net "GND")
			(clearance -1.7145)
			(thermal_gap 0.3048)
			(padstack
				(mode front_inner_back)
				(layer "Inner"
					(shape circle)
					(size 3.9624 3.9624)
					(clearance 0.3048)
				)
				(layer "B.Cu"
					(shape circle)
					(size 8.001 8.001)
					(clearance -1.7145)
				)
			)
		)
	)
	(footprint ""
		(layer "F.Cu")
		(at 18.415 -87.63 -90)
		(property "Reference" "PR20"
			(at 0 0 270)
			(layer "F.SilkS")
			(hide yes)
			(effects
				(font
					(size 1.27 1.27)
				)
			)
		)
		(property "Value" "10KR2F-2-GP"
			(at 0.064008 -3.993896 270)
			(unlocked yes)
			(layer "F.Fab")
			(hide yes)
			(effects
				(font
					(size 1.016 1.016)
					(thickness 0.1524)
				)
			)
		)
		(property "Device Type" "R402H16"
			(at 0.064008 -5.517896 270)
			(unlocked yes)
			(layer "F.Fab")
			(hide yes)
			(effects
				(font
					(size 1.016 1.016)
					(thickness 0.1524)
				)
			)
		)
		(duplicate_pad_numbers_are_jumpers no)
		(fp_line
			(start -0.508 -0.9398)
			(end -0.508 0.9398)
			(stroke
				(width 0.1524)
				(type default)
			)
			(layer "F.SilkS")
		)
		(fp_line
			(start 0.508 -0.9398)
			(end -0.508 -0.9398)
			(stroke
				(width 0.1524)
				(type default)
			)
			(layer "F.SilkS")
		)
		(fp_rect
			(start -0.508 0.9398)
			(end 0.508 -0.9398)
			(stroke
				(width 0)
				(type default)
			)
			(fill no)
			(layer "F.CrtYd")
		)
		(fp_rect
			(start -0.508 0.9398)
			(end 0.508 -0.9398)
			(stroke
				(width 0)
				(type default)
			)
			(fill no)
			(layer "F.Fab")
		)
		(pad "1" smd custom
			(at 0 -0.4445 270)
			(size 0.1397 0.1397)
			(layers "F.Cu" "F.Mask" "F.Paste")
			(net "P3V3_PWR")
			(options
				(clearance outline)
				(anchor circle)
			)
			(primitives
				(gr_poly
					(pts
						(arc
							(start -0.1778 -0.2794)
							(mid -0.249642 -0.249642)
							(end -0.2794 -0.1778)
						)
						(arc
							(start -0.2794 0.1778)
							(mid -0.249642 0.249642)
							(end -0.1778 0.2794)
						)
						(arc
							(start 0.1778 0.2794)
							(mid 0.249642 0.249642)
							(end 0.2794 0.1778)
						)
						(arc
							(start 0.2794 -0.1778)
							(mid 0.249642 -0.249642)
							(end 0.1778 -0.2794)
						)
					)
					(width 0)
					(fill yes)
				)
			)
		)
		(pad "2" smd custom
			(at 0 0.4445 270)
			(size 0.1397 0.1397)
			(layers "F.Cu" "F.Mask" "F.Paste")
			(net "P1V8_PWR_GD")
			(options
				(clearance outline)
				(anchor circle)
			)
			(primitives
				(gr_poly
					(pts
						(arc
							(start -0.1778 -0.2794)
							(mid -0.249642 -0.249642)
							(end -0.2794 -0.1778)
						)
						(arc
							(start -0.2794 0.1778)
							(mid -0.249642 0.249642)
							(end -0.1778 0.2794)
						)
						(arc
							(start 0.1778 0.2794)
							(mid 0.249642 0.249642)
							(end 0.2794 0.1778)
						)
						(arc
							(start 0.2794 -0.1778)
							(mid 0.249642 -0.249642)
							(end 0.1778 -0.2794)
						)
					)
					(width 0)
					(fill yes)
				)
			)
		)
	)
	(footprint ""
		(layer "F.Cu")
		(at 43.053 -84.709 180)
		(property "Reference" "PC31"
			(at 0 0 180)
			(layer "F.SilkS")
			(hide yes)
			(effects
				(font
					(size 1.27 1.27)
				)
			)
		)
		(property "Value" "SCD1U25V3KX-GP"
			(at 0 -2.8194 180)
			(unlocked yes)
			(layer "F.Fab")
			(hide yes)
			(effects
				(font
					(size 1.016 1.016)
					(thickness 0.1524)
				)
			)
		)
		(property "Device Type" "C603H36"
			(at 0 -4.3434 180)
			(unlocked yes)
			(layer "F.Fab")
			(hide yes)
			(effects
				(font
					(size 1.016 1.016)
					(thickness 0.1524)
				)
			)
		)
		(duplicate_pad_numbers_are_jumpers no)
		(fp_line
			(start 0.508 0)
			(end -0.508 0)
			(stroke
				(width 0.2032)
				(type default)
			)
			(layer "F.SilkS")
		)
		(fp_rect
			(start -0.5842 1.3335)
			(end 0.5842 -1.3335)
			(stroke
				(width 0)
				(type default)
			)
			(fill no)
			(layer "F.CrtYd")
		)
		(fp_rect
			(start -0.5842 1.3335)
			(end 0.5842 -1.3335)
			(stroke
				(width 0)
				(type default)
			)
			(fill no)
			(layer "F.Fab")
		)
		(pad "1" smd custom
			(at 0 -0.762 180)
			(size 0.2159 0.2159)
			(layers "F.Cu" "F.Mask" "F.Paste")
			(net "P3V3_DEV_VIN")
			(options
				(clearance outline)
				(anchor circle)
			)
			(primitives
				(gr_poly
					(pts
						(arc
							(start -0.3302 -0.4318)
							(mid -0.402042 -0.402042)
							(end -0.4318 -0.3302)
						)
						(arc
							(start -0.4318 0.3302)
							(mid -0.402042 0.402042)
							(end -0.3302 0.4318)
						)
						(arc
							(start 0.3302 0.4318)
							(mid 0.402042 0.402042)
							(end 0.4318 0.3302)
						)
						(arc
							(start 0.4318 -0.3302)
							(mid 0.402042 -0.402042)
							(end 0.3302 -0.4318)
						)
					)
					(width 0)
					(fill yes)
				)
			)
		)
		(pad "2" smd custom
			(at 0 0.762 180)
			(size 0.2159 0.2159)
			(layers "F.Cu" "F.Mask" "F.Paste")
			(net "GND")
			(options
				(clearance outline)
				(anchor circle)
			)
			(primitives
				(gr_poly
					(pts
						(arc
							(start -0.3302 -0.4318)
							(mid -0.402042 -0.402042)
							(end -0.4318 -0.3302)
						)
						(arc
							(start -0.4318 0.3302)
							(mid -0.402042 0.402042)
							(end -0.3302 0.4318)
						)
						(arc
							(start 0.3302 0.4318)
							(mid 0.402042 0.402042)
							(end 0.4318 0.3302)
						)
						(arc
							(start 0.4318 -0.3302)
							(mid 0.402042 -0.402042)
							(end 0.3302 -0.4318)
						)
					)
					(width 0)
					(fill yes)
				)
			)
		)
	)
	(footprint ""
		(layer "F.Cu")
		(at 48.133 -86.36)
		(property "Reference" "PR33"
			(at 0 0 0)
			(layer "F.SilkS")
			(hide yes)
			(effects
				(font
					(size 1.27 1.27)
				)
			)
		)
		(property "Value" "3D01R5F-GP"
			(at 0 -8.9535 0)
			(unlocked yes)
			(layer "F.Fab")
			(hide yes)
			(effects
				(font
					(size 1.27 1.016)
					(thickness 0.1524)
				)
			)
		)
		(property "Device Type" "R805H24"
			(at 0 -10.6299 0)
			(unlocked yes)
			(layer "F.Fab")
			(hide yes)
			(effects
				(font
					(size 1.27 1.016)
					(thickness 0.1524)
				)
			)
		)
		(duplicate_pad_numbers_are_jumpers no)
		(fp_line
			(start -0.889 -1.7018)
			(end -0.889 0.2794)
			(stroke
				(width 0.1524)
				(type default)
			)
			(layer "F.SilkS")
		)
		(fp_line
			(start -0.889 0.0762)
			(end -0.889 1.7018)
			(stroke
				(width 0.1524)
				(type default)
			)
			(layer "F.SilkS")
		)
		(fp_line
			(start -0.889 1.7018)
			(end 0.889 1.7018)
			(stroke
				(width 0.1524)
				(type default)
			)
			(layer "F.SilkS")
		)
		(fp_line
			(start 0.889 -1.7018)
			(end -0.889 -1.7018)
			(stroke
				(width 0.1524)
				(type default)
			)
			(layer "F.SilkS")
		)
		(fp_line
			(start 0.889 -1.7018)
			(end 0.889 -0.381)
			(stroke
				(width 0.1524)
				(type default)
			)
			(layer "F.SilkS")
		)
		(fp_line
			(start 0.889 1.7018)
			(end 0.889 -0.508)
			(stroke
				(width 0.1524)
				(type default)
			)
			(layer "F.SilkS")
		)
		(fp_poly
			(pts
				(xy 0.9652 -1.778) (xy 0.9652 1.778) (xy -0.9652 1.778) (xy -0.9652 -1.778)
			)
			(stroke
				(width 0)
				(type default)
			)
			(fill no)
			(layer "F.CrtYd")
		)
		(fp_rect
			(start -0.9652 1.778)
			(end 0.9652 -1.778)
			(stroke
				(width 0)
				(type default)
			)
			(fill no)
			(layer "F.Fab")
		)
		(pad "1" smd rect
			(at 0 -0.9652)
			(size 1.397 1.143)
			(layers "F.Cu" "F.Mask" "F.Paste")
			(net "P3V3_DEV_SNB")
		)
		(pad "2" smd rect
			(at 0 0.9652)
			(size 1.397 1.143)
			(layers "F.Cu" "F.Mask" "F.Paste")
			(net "GND")
		)
	)
	(footprint ""
		(layer "F.Cu")
		(at 17.272 -86.154006)
		(property "Reference" "TP5"
			(at 0 0 0)
			(layer "F.SilkS")
			(hide yes)
			(effects
				(font
					(size 1.27 1.27)
				)
			)
		)
		(property "Value" "TPAD28-1-GP-U"
			(at 0.0508 -1.9304 0)
			(unlocked yes)
			(layer "F.Fab")
			(hide yes)
			(effects
				(font
					(size 1.016 1.016)
					(thickness 0.1524)
				)
			)
		)
		(property "Device Type" "TPAD28-1-U"
			(at 0.0508 -3.4544 0)
			(unlocked yes)
			(layer "F.Fab")
			(hide yes)
			(effects
				(font
					(size 1.016 1.016)
					(thickness 0.1524)
				)
			)
		)
		(duplicate_pad_numbers_are_jumpers no)
		(fp_poly
			(pts
				(arc
					(start 0.3556 0)
					(mid -0.3556 0)
					(end 0.3556 0)
				)
			)
			(stroke
				(width 0)
				(type default)
			)
			(fill no)
			(layer "F.CrtYd")
		)
		(fp_poly
			(pts
				(arc
					(start 0.9525 0)
					(mid -0.9525 0)
					(end 0.9525 0)
				)
			)
			(stroke
				(width 0)
				(type default)
			)
			(fill no)
			(layer "F.Fab")
		)
		(pad "1" smd circle
			(at 0 0)
			(size 0.7112 0.7112)
			(layers "F.Cu" "F.Mask" "F.Paste")
			(net "P1V8_PWR_GD")
		)
	)
	(footprint ""
		(layer "F.Cu")
		(at 20.447 -72.565006 90)
		(property "Reference" "PC23"
			(at 0 0 90)
			(layer "F.SilkS")
			(hide yes)
			(effects
				(font
					(size 1.27 1.27)
				)
			)
		)
		(property "Value" "SC4D7U16V5KX-1-GP"
			(at -0.0762 -6.1214 90)
			(unlocked yes)
			(layer "F.Fab")
			(hide yes)
			(effects
				(font
					(size 1.016 1.016)
					(thickness 0.1524)
				)
			)
		)
		(property "Device Type" "C805H56"
			(at -0.0762 -8.1534 90)
			(unlocked yes)
			(layer "F.Fab")
			(hide yes)
			(effects
				(font
					(size 1.016 1.016)
					(thickness 0.1524)
				)
			)
		)
		(duplicate_pad_numbers_are_jumpers no)
		(fp_line
			(start 0.635 0)
			(end -0.635 0)
			(stroke
				(width 0.508)
				(type default)
			)
			(layer "F.SilkS")
		)
		(fp_rect
			(start -0.9652 1.778)
			(end 0.9652 -1.778)
			(stroke
				(width 0)
				(type default)
			)
			(fill no)
			(layer "F.CrtYd")
		)
		(fp_poly
			(pts
				(xy -0.9652 -1.778) (xy 0.9652 -1.778) (xy 0.9652 1.778) (xy -0.9652 1.778)
			)
			(stroke
				(width 0)
				(type default)
			)
			(fill no)
			(layer "F.Fab")
		)
		(pad "1" smd rect
			(at 0 -0.9652 90)
			(size 1.397 1.143)
			(layers "F.Cu" "F.Mask" "F.Paste")
			(net "P1V8_PWR")
		)
		(pad "2" smd rect
			(at 0 0.9652 90)
			(size 1.397 1.143)
			(layers "F.Cu" "F.Mask" "F.Paste")
			(net "GND")
		)
	)
	(footprint ""
		(layer "F.Cu")
		(at 75.692 -38.735 180)
		(property "Reference" "R45"
			(at 0 0 180)
			(layer "F.SilkS")
			(hide yes)
			(effects
				(font
					(size 1.27 1.27)
				)
			)
		)
		(property "Value" "47KR2F-GP"
			(at 0.064008 -3.993896 180)
			(unlocked yes)
			(layer "F.Fab")
			(hide yes)
			(effects
				(font
					(size 1.016 1.016)
					(thickness 0.1524)
				)
			)
		)
		(property "Device Type" "R402H16"
			(at 0.064008 -5.517896 180)
			(unlocked yes)
			(layer "F.Fab")
			(hide yes)
			(effects
				(font
					(size 1.016 1.016)
					(thickness 0.1524)
				)
			)
		)
		(duplicate_pad_numbers_are_jumpers no)
		(fp_line
			(start 0.508 -0.9398)
			(end -0.508 -0.9398)
			(stroke
				(width 0.1524)
				(type default)
			)
			(layer "F.SilkS")
		)
		(fp_line
			(start -0.508 -0.9398)
			(end -0.508 0.9398)
			(stroke
				(width 0.1524)
				(type default)
			)
			(layer "F.SilkS")
		)
		(fp_rect
			(start -0.508 0.9398)
			(end 0.508 -0.9398)
			(stroke
				(width 0)
				(type default)
			)
			(fill no)
			(layer "F.CrtYd")
		)
		(fp_rect
			(start -0.508 0.9398)
			(end 0.508 -0.9398)
			(stroke
				(width 0)
				(type default)
			)
			(fill no)
			(layer "F.Fab")
		)
		(pad "1" smd custom
			(at 0 -0.4445 180)
			(size 0.1397 0.1397)
			(layers "F.Cu" "F.Mask" "F.Paste")
			(net "P3V3_DPB")
			(options
				(clearance outline)
				(anchor circle)
			)
			(primitives
				(gr_poly
					(pts
						(arc
							(start -0.1778 -0.2794)
							(mid -0.249642 -0.249642)
							(end -0.2794 -0.1778)
						)
						(arc
							(start -0.2794 0.1778)
							(mid -0.249642 0.249642)
							(end -0.1778 0.2794)
						)
						(arc
							(start 0.1778 0.2794)
							(mid 0.249642 0.249642)
							(end 0.2794 0.1778)
						)
						(arc
							(start 0.2794 -0.1778)
							(mid 0.249642 -0.249642)
							(end 0.1778 -0.2794)
						)
					)
					(width 0)
					(fill yes)
				)
			)
		)
		(pad "2" smd custom
			(at 0 0.4445 180)
			(size 0.1397 0.1397)
			(layers "F.Cu" "F.Mask" "F.Paste")
			(net "Z50_SSD_B_PRSNT#")
			(options
				(clearance outline)
				(anchor circle)
			)
			(primitives
				(gr_poly
					(pts
						(arc
							(start -0.1778 -0.2794)
							(mid -0.249642 -0.249642)
							(end -0.2794 -0.1778)
						)
						(arc
							(start -0.2794 0.1778)
							(mid -0.249642 0.249642)
							(end -0.1778 0.2794)
						)
						(arc
							(start 0.1778 0.2794)
							(mid 0.249642 0.249642)
							(end 0.2794 0.1778)
						)
						(arc
							(start 0.2794 -0.1778)
							(mid 0.249642 -0.249642)
							(end 0.1778 -0.2794)
						)
					)
					(width 0)
					(fill yes)
				)
			)
		)
	)
	(footprint ""
		(layer "F.Cu")
		(at 14.732 -80.693006 180)
		(property "Reference" "PR24"
			(at 0 0 180)
			(layer "F.SilkS")
			(hide yes)
			(effects
				(font
					(size 1.27 1.27)
				)
			)
		)
		(property "Value" "0R3F-1-GP-U"
			(at -0.0254 -2.5146 180)
			(unlocked yes)
			(layer "F.Fab")
			(hide yes)
			(effects
				(font
					(size 1.016 1.016)
					(thickness 0.1524)
				)
			)
		)
		(property "Device Type" "R603H24"
			(at -0.0254 -4.0386 180)
			(unlocked yes)
			(layer "F.Fab")
			(hide yes)
			(effects
				(font
					(size 1.016 1.016)
					(thickness 0.1524)
				)
			)
		)
		(duplicate_pad_numbers_are_jumpers no)
		(fp_line
			(start 0.2032 0)
			(end 0.4826 0)
			(stroke
				(width 0.2032)
				(type default)
			)
			(layer "F.SilkS")
		)
		(fp_line
			(start -0.4826 0)
			(end -0.2032 0)
			(stroke
				(width 0.2032)
				(type default)
			)
			(layer "F.SilkS")
		)
		(fp_rect
			(start -0.5842 1.3335)
			(end 0.5842 -1.3335)
			(stroke
				(width 0)
				(type default)
			)
			(fill no)
			(layer "F.CrtYd")
		)
		(fp_rect
			(start -0.5842 1.3335)
			(end 0.5842 -1.3335)
			(stroke
				(width 0)
				(type default)
			)
			(fill no)
			(layer "F.Fab")
		)
		(pad "1" smd custom
			(at 0 -0.762 180)
			(size 0.2159 0.2159)
			(layers "F.Cu" "F.Mask" "F.Paste")
			(net "P3V3_PWR")
			(options
				(clearance outline)
				(anchor circle)
			)
			(primitives
				(gr_poly
					(pts
						(arc
							(start -0.3302 -0.4318)
							(mid -0.402042 -0.402042)
							(end -0.4318 -0.3302)
						)
						(arc
							(start -0.4318 0.3302)
							(mid -0.402042 0.402042)
							(end -0.3302 0.4318)
						)
						(arc
							(start 0.3302 0.4318)
							(mid 0.402042 0.402042)
							(end 0.4318 0.3302)
						)
						(arc
							(start 0.4318 -0.3302)
							(mid 0.402042 -0.402042)
							(end 0.3302 -0.4318)
						)
					)
					(width 0)
					(fill yes)
				)
			)
		)
		(pad "2" smd custom
			(at 0 0.762 180)
			(size 0.2159 0.2159)
			(layers "F.Cu" "F.Mask" "F.Paste")
			(net "P1V8_PWR_EN_R")
			(options
				(clearance outline)
				(anchor circle)
			)
			(primitives
				(gr_poly
					(pts
						(arc
							(start -0.3302 -0.4318)
							(mid -0.402042 -0.402042)
							(end -0.4318 -0.3302)
						)
						(arc
							(start -0.4318 0.3302)
							(mid -0.402042 0.402042)
							(end -0.3302 0.4318)
						)
						(arc
							(start 0.3302 0.4318)
							(mid 0.402042 0.402042)
							(end 0.4318 0.3302)
						)
						(arc
							(start 0.4318 -0.3302)
							(mid 0.402042 -0.402042)
							(end 0.3302 -0.4318)
						)
					)
					(width 0)
					(fill yes)
				)
			)
		)
	)
	(footprint ""
		(layer "F.Cu")
		(at 29.083 -72.009)
		(property "Reference" "R53"
			(at 0 0 0)
			(layer "F.SilkS")
			(hide yes)
			(effects
				(font
					(size 1.27 1.27)
				)
			)
		)
		(property "Value" "33R2J-2-GP"
			(at 0.064008 -3.993896 0)
			(unlocked yes)
			(layer "F.Fab")
			(hide yes)
			(effects
				(font
					(size 1.016 1.016)
					(thickness 0.1524)
				)
			)
		)
		(property "Device Type" "R402H16"
			(at 0.064008 -5.517896 0)
			(unlocked yes)
			(layer "F.Fab")
			(hide yes)
			(effects
				(font
					(size 1.016 1.016)
					(thickness 0.1524)
				)
			)
		)
		(duplicate_pad_numbers_are_jumpers no)
		(fp_line
			(start -0.508 -0.9398)
			(end -0.508 0.9398)
			(stroke
				(width 0.1524)
				(type default)
			)
			(layer "F.SilkS")
		)
		(fp_line
			(start 0.508 -0.9398)
			(end -0.508 -0.9398)
			(stroke
				(width 0.1524)
				(type default)
			)
			(layer "F.SilkS")
		)
		(fp_rect
			(start -0.508 0.9398)
			(end 0.508 -0.9398)
			(stroke
				(width 0)
				(type default)
			)
			(fill no)
			(layer "F.CrtYd")
		)
		(fp_rect
			(start -0.508 0.9398)
			(end 0.508 -0.9398)
			(stroke
				(width 0)
				(type default)
			)
			(fill no)
			(layer "F.Fab")
		)
		(pad "1" smd custom
			(at 0 -0.4445)
			(size 0.1397 0.1397)
			(layers "F.Cu" "F.Mask" "F.Paste")
			(net "Z50_SSD_B1_SMB_CLK_LR")
			(options
				(clearance outline)
				(anchor circle)
			)
			(primitives
				(gr_poly
					(pts
						(arc
							(start -0.1778 -0.2794)
							(mid -0.249642 -0.249642)
							(end -0.2794 -0.1778)
						)
						(arc
							(start -0.2794 0.1778)
							(mid -0.249642 0.249642)
							(end -0.1778 0.2794)
						)
						(arc
							(start 0.1778 0.2794)
							(mid 0.249642 0.249642)
							(end 0.2794 0.1778)
						)
						(arc
							(start 0.2794 -0.1778)
							(mid 0.249642 -0.249642)
							(end 0.1778 -0.2794)
						)
					)
					(width 0)
					(fill yes)
				)
			)
		)
		(pad "2" smd custom
			(at 0 0.4445)
			(size 0.1397 0.1397)
			(layers "F.Cu" "F.Mask" "F.Paste")
			(net "Z50_SSD_B1_SMB_CLK")
			(options
				(clearance outline)
				(anchor circle)
			)
			(primitives
				(gr_poly
					(pts
						(arc
							(start -0.1778 -0.2794)
							(mid -0.249642 -0.249642)
							(end -0.2794 -0.1778)
						)
						(arc
							(start -0.2794 0.1778)
							(mid -0.249642 0.249642)
							(end -0.1778 0.2794)
						)
						(arc
							(start 0.1778 0.2794)
							(mid 0.249642 0.249642)
							(end 0.2794 0.1778)
						)
						(arc
							(start 0.2794 -0.1778)
							(mid 0.249642 -0.249642)
							(end 0.1778 -0.2794)
						)
					)
					(width 0)
					(fill yes)
				)
			)
		)
	)
)
